# S9S_MB_2U (Grand Teton) — schematic netlist excerpt (pin names and nets, part order shuffled) for the footprints in the layout excerpt that follows; sources: Cadence DE-HDL packaged netlist, KiCad conversion of 03242023_DA0F0TMBIJ0_F0T_Motherboard_J_brd_V01_OCP.brd

J20  SCONN288_ADR50017P087CC  SCONN288_ADR50017-P087CC IO  pkg DDR288S_1-1VXB  page 101
  VIN_BULK0  = P12V_S3_AUX_CPU1_NVDIMM
  RFU0  = TP_CHB_CPU1_DIMM2_FRU_0
  VIN_MGMT  = P3V3_AUX
  HSCL  = I3C_SPD_DDRABCD_CPU1_LVC1_SCL_3
  HSDA  = I3C_SPD_DDRABCD_CPU1_LVC1_SDA
  VSS0  = GND
  DQ0_A  = M_B_CPU1_SA_DQ<0>
  VSS1  = GND
  DQ1_A  = M_B_CPU1_SA_DQ<1>
  VSS2  = GND
  DQS0_A_T  = M_B_CPU1_SA_DQS_DP<0>
  DQS0_A_C  = M_B_CPU1_SA_DQS_DN<0>
  VSS3  = GND
  DQ4_A  = M_B_CPU1_SA_DQ<4>
  VSS4  = GND
  DQ5_A  = M_B_CPU1_SA_DQ<5>
  VSS5  = GND
  DQ8_A  = M_B_CPU1_SA_DQ<8>
  VSS6  = GND
  DQ9_A  = M_B_CPU1_SA_DQ<9>
  VSS7  = GND
  DQS1_A_T  = M_B_CPU1_SA_DQS_DP<1>
  DQS1_A_C  = M_B_CPU1_SA_DQS_DN<1>
  VSS8  = GND
  DQ12_A  = M_B_CPU1_SA_DQ<12>
  VSS9  = GND
  DQ13_A  = M_B_CPU1_SA_DQ<13>
  VSS10  = GND
  DQ16_A  = M_B_CPU1_SA_DQ<16>
  VSS11  = GND
  DQ17_A  = M_B_CPU1_SA_DQ<17>
  VSS12  = GND
  DQS2_A_T  = M_B_CPU1_SA_DQS_DP<2>
  DQS2_A_C  = M_B_CPU1_SA_DQS_DN<2>
  VSS13  = GND
  DQ20_A  = M_B_CPU1_SA_DQ<20>
  VSS14  = GND
  DQ21_A  = M_B_CPU1_SA_DQ<21>
  VSS15  = GND
  DQ24_A  = M_B_CPU1_SA_DQ<24>
  VSS16  = GND
  DQ25_A  = M_B_CPU1_SA_DQ<25>
  VSS17  = GND
  DQS3_A_T  = M_B_CPU1_SA_DQS_DP<3>
  DQS3_A_C  = M_B_CPU1_SA_DQS_DN<3>
  VSS18  = GND
  DQ28_A  = M_B_CPU1_SA_DQ<28>
  VSS19  = GND
  DQ29_A  = M_B_CPU1_SA_DQ<29>
  VSS20  = GND
  CB0_A  = M_B_CPU1_SA_CB<0>
  VSS21  = GND
  CB1_A  = M_B_CPU1_SA_CB<1>
  VSS22  = GND
  DQS4_A_T  = M_B_CPU1_SA_DQS_DP<4>
  DQS4_A_C  = M_B_CPU1_SA_DQS_DN<4>
  VSS23  = GND
  CB4_A  = M_B_CPU1_SA_CB<4>
  VSS24  = GND
  CB5_A  = M_B_CPU1_SA_CB<5>
  VSS25  = GND
  ALERT_N  = M_B_CPU1_ALERT_N
  VSS26  = GND
  CS0_A_N  = M_B_CPU1_SA_CS_N<2>
  VSS27  = GND
  CA0_A  = M_B_CPU1_SA_CA<0>
  VSS28  = GND
  CA2_A  = M_B_CPU1_SA_CA<2>
  VSS29  = GND
  CA4_A  = M_B_CPU1_SA_CA<4>
  VSS30  = GND
  CA6_A  = M_B_CPU1_SA_CA<6>
  VSS31  = GND
  PAR_A  = M_B_CPU1_SA_PAR
  VSS32  = GND
  CA0_B  = M_B_CPU1_SB_CA<0>
  VSS33  = GND
  CA2_B  = M_B_CPU1_SB_CA<2>
  VSS34  = GND
  CA4_B  = M_B_CPU1_SB_CA<4>
  VSS35  = GND
  CA6_B  = M_B_CPU1_SB_CA<6>
  VSS36  = GND
  CS0_B_N  = M_B_CPU1_SB_CS_N<2>
  VSS37  = GND
  \lbd||rsp_a_n\  = M_B_CPU1_SA_RSP<1>
  \lbs||rsp_b_n\  = M_B_CPU1_SB_RSP<1>
  VSS38  = GND
  CB4_B  = M_B_CPU1_SB_CB<4>
  VSS39  = GND
  CB5_B  = M_B_CPU1_SB_CB<5>
  VSS40  = GND
  \dqs9_b_t||tdqs9_b_t||dbi4_b_n\  = M_B_CPU1_SB_DQS_DP<9>
  \dqs9_b_c||tdqs9_b_c\  = M_B_CPU1_SB_DQS_DN<9>
  VSS41  = GND
  CB0_B  = M_B_CPU1_SB_CB<0>
  VSS42  = GND
  CB1_B  = M_B_CPU1_SB_CB<1>
  VSS43  = GND
  DQ0_B  = M_B_CPU1_SB_DQ<0>
  VSS44  = GND
  DQ1_B  = M_B_CPU1_SB_DQ<1>
  VSS45  = GND
  DQS0_B_T  = M_B_CPU1_SB_DQS_DP<0>
  DQS0_B_C  = M_B_CPU1_SB_DQS_DN<0>
  VSS46  = GND
  DQ4_B  = M_B_CPU1_SB_DQ<4>
  VSS47  = GND
  DQ5_B  = M_B_CPU1_SB_DQ<5>
  VSS48  = GND
  DQ8_B  = M_B_CPU1_SB_DQ<8>
  VSS49  = GND
  DQ9_B  = M_B_CPU1_SB_DQ<9>
  VSS50  = GND
  DQS1_B_T  = M_B_CPU1_SB_DQS_DP<1>
  DQS1_B_C  = M_B_CPU1_SB_DQS_DN<1>
  VSS51  = GND
  DQ12_B  = M_B_CPU1_SB_DQ<12>
  VSS52  = GND
  DQ13_B  = M_B_CPU1_SB_DQ<13>
  VSS53  = GND
  DQ16_B  = M_B_CPU1_SB_DQ<16>
  VSS54  = GND
  DQ17_B  = M_B_CPU1_SB_DQ<17>
  VSS55  = GND
  DQS2_B_T  = M_B_CPU1_SB_DQS_DP<2>
  DQS2_B_C  = M_B_CPU1_SB_DQS_DN<2>
  VSS56  = GND
  DQ20_B  = M_B_CPU1_SB_DQ<20>
  VSS57  = GND
  DQ21_B  = M_B_CPU1_SB_DQ<21>
  VSS58  = GND
  DQ24_B  = M_B_CPU1_SB_DQ<24>
  VSS59  = GND
  DQ25_B  = M_B_CPU1_SB_DQ<25>
  VSS60  = GND
  DQS3_B_T  = M_B_CPU1_SB_DQS_DP<3>
  DQS3_B_C  = M_B_CPU1_SB_DQS_DN<3>
  VSS61  = GND
  DQ28_B  = M_B_CPU1_SB_DQ<28>
  VSS62  = GND
  DQ29_B  = M_B_CPU1_SB_DQ<29>
  VSS63  = GND
  RFU1  = TP_CHB_CPU1_DIMM2_FRU_1
  VIN_BULK1  = P12V_S3_AUX_CPU1_NVDIMM
  VIN_BULK2  = P12V_S3_AUX_CPU1_NVDIMM
  \pwr_good||fail_n\  = PWRGD_CHB_CPU1_DIMM2
  HSA  = PD_CHB_CPU1_DIMM2_SAA
  RFU2  = TP_CHB_CPU1_DIMM2_FRU_2
  RFU3  = TP_CHB_CPU1_DIMM2_FRU_3
  VSS64  = GND
  DQ2_A  = M_B_CPU1_SA_DQ<2>
  VSS65  = GND
  DQ3_A  = M_B_CPU1_SA_DQ<3>
  VSS66  = GND
  \dqs5_a_c||tdqs5_a_c||dqs5_a_t||tdqs5_a_t\  = M_B_CPU1_SA_DQS_DN<5>
  \dqs5_a_t||tdqs5_a_t\  = M_B_CPU1_SA_DQS_DP<5>
  VSS67  = GND
  DQ6_A  = M_B_CPU1_SA_DQ<6>
  VSS68  = GND
  DQ7_A  = M_B_CPU1_SA_DQ<7>
  VSS69  = GND
  DQ10_A  = M_B_CPU1_SA_DQ<10>
  VSS70  = GND
  DQ11_A  = M_B_CPU1_SA_DQ<11>
  VSS71  = GND
  \dqs6_a_c||tdqs6_a_c||dqs6_a_t||tdqs6_a_t\  = M_B_CPU1_SA_DQS_DN<6>
  \dqs6_a_t||tdqs6_a_t\  = M_B_CPU1_SA_DQS_DP<6>
  VSS72  = GND
  DQ14_A  = M_B_CPU1_SA_DQ<14>
  VSS73  = GND
  DQ15_A  = M_B_CPU1_SA_DQ<15>
  VSS74  = GND
  DQ18_A  = M_B_CPU1_SA_DQ<18>
  VSS75  = GND
  DQ19_A  = M_B_CPU1_SA_DQ<19>
  VSS76  = GND
  \dqs7_a_c||tdqs7_a_c\  = M_B_CPU1_SA_DQS_DN<7>
  \dqs7_a_t||tdqs7_a_t\  = M_B_CPU1_SA_DQS_DP<7>
  VSS77  = GND
  DQ22_A  = M_B_CPU1_SA_DQ<22>
  VSS78  = GND
  DQ23_A  = M_B_CPU1_SA_DQ<23>
  VSS79  = GND
  DQ26_A  = M_B_CPU1_SA_DQ<26>
  VSS80  = GND
  DQ27_A  = M_B_CPU1_SA_DQ<27>
  VSS81  = GND
  \dqs8_a_c||tdqs8_a_c\  = M_B_CPU1_SA_DQS_DN<8>
  \dqs8_a_t||tdqs8_a_t\  = M_B_CPU1_SA_DQS_DP<8>
  VSS82  = GND
  DQ30_A  = M_B_CPU1_SA_DQ<30>
  VSS83  = GND
  DQ31_A  = M_B_CPU1_SA_DQ<31>
  VSS84  = GND
  CB2_A  = M_B_CPU1_SA_CB<2>
  VSS85  = GND
  CB3_A  = M_B_CPU1_SA_CB<3>
  VSS86  = GND
  \dqs9_a_c||tdqs9_a_c\  = M_B_CPU1_SA_DQS_DN<9>
  \dqs9_a_t||tdqs9_a_t\  = M_B_CPU1_SA_DQS_DP<9>
  VSS87  = GND
  CB6_A  = M_B_CPU1_SA_CB<6>
  VSS88  = GND
  CB7_A  = M_B_CPU1_SA_CB<7>
  VSS89  = GND
  RESET_N  = RST_M_AB_CPU1_FPGA_N
  VSS90  = GND
  CS1_A_N  = M_B_CPU1_SA_CS_N<3>
  VSS91  = GND
  CA1_A  = M_B_CPU1_SA_CA<1>
  VSS92  = GND
  CA3_A  = M_B_CPU1_SA_CA<3>
  VSS93  = GND
  CA5_A  = M_B_CPU1_SA_CA<5>
  VSS94  = GND
  CK_T  = M_B_CPU1_CLK_DP<1>
  CK_C  = M_B_CPU1_CLK_DN<1>
  VSS95  = GND
  RFU4  = TP_CHB_CPU1_DIMM2_FRU_4
  CA1_B  = M_B_CPU1_SB_CA<1>
  VSS96  = GND
  CA3_B  = M_B_CPU1_SB_CA<3>
  VSS97  = GND
  CA5_B  = M_B_CPU1_SB_CA<5>
  VSS98  = GND
  PAR_B  = M_B_CPU1_SB_PAR
  VSS99  = GND
  CS1_B_N  = M_B_CPU1_SB_CS_N<3>
  VSS100  = GND
  RFU5  = TP_CHB_CPU1_DIMM2_FRU_5
  RFU6  = TP_CHB_CPU1_DIMM2_FRU_6
  VSS101  = GND
  CB6_B  = M_B_CPU1_SB_CB<6>
  VSS102  = GND
  CB7_B  = M_B_CPU1_SB_CB<7>
  VSS103  = GND
  DQS4_B_C  = M_B_CPU1_SB_DQS_DN<4>
  DQS4_B_T  = M_B_CPU1_SB_DQS_DP<4>
  VSS104  = GND
  CB2_B  = M_B_CPU1_SB_CB<2>
  VSS105  = GND
  CB3_B  = M_B_CPU1_SB_CB<3>
  VSS106  = GND
  DQ2_B  = M_B_CPU1_SB_DQ<2>
  VSS107  = GND
  DQ3_B  = M_B_CPU1_SB_DQ<3>
  VSS108  = GND
  \dqs5_b_c||tdqs5_b_c\  = M_B_CPU1_SB_DQS_DN<5>
  \dqs5_b_t||tdqs5_b_t\  = M_B_CPU1_SB_DQS_DP<5>
  VSS109  = GND
  DQ6_B  = M_B_CPU1_SB_DQ<6>
  VSS110  = GND
  DQ7_B  = M_B_CPU1_SB_DQ<7>
  VSS111  = GND
  DQ10_B  = M_B_CPU1_SB_DQ<10>
  VSS112  = GND
  DQ11_B  = M_B_CPU1_SB_DQ<11>
  VSS113  = GND
  \dqs6_b_c||tdqs6_b_c\  = M_B_CPU1_SB_DQS_DN<6>
  \dqs6_b_t||tdqs6_b_t\  = M_B_CPU1_SB_DQS_DP<6>
  VSS114  = GND
  DQ14_B  = M_B_CPU1_SB_DQ<14>
  VSS115  = GND
  DQ15_B  = M_B_CPU1_SB_DQ<15>
  VSS116  = GND
  DQ18_B  = M_B_CPU1_SB_DQ<18>
  VSS117  = GND
  DQ19_B  = M_B_CPU1_SB_DQ<19>
  VSS118  = GND
  \dqs7_b_c||tdqs7_b_c\  = M_B_CPU1_SB_DQS_DN<7>
  \dqs7_b_t||tdqs7_b_t\  = M_B_CPU1_SB_DQS_DP<7>
  VSS119  = GND
  DQ22_B  = M_B_CPU1_SB_DQ<22>
  VSS120  = GND
  DQ23_B  = M_B_CPU1_SB_DQ<23>
  VSS121  = GND
  DQ26_B  = M_B_CPU1_SB_DQ<26>
  VSS122  = GND
  DQ27_B  = M_B_CPU1_SB_DQ<27>
  VSS123  = GND
  \dqs8_b_c||tdqs8_b_c\  = M_B_CPU1_SB_DQS_DN<8>
  \dqs8_b_t||tdqs8_b_t\  = M_B_CPU1_SB_DQS_DP<8>
  VSS124  = GND
  DQ30_B  = M_B_CPU1_SB_DQ<30>
  VSS125  = GND
  DQ31_B  = M_B_CPU1_SB_DQ<31>
  VSS126  = GND
  G1  = GND
  G2  = GND
  G3  = GND

(kicad_pcb
	(version 20260206)
	(generator "pcbnew")
	(generator_version "10.0")
	(general
		(thickness 1.6)
		(legacy_teardrops no)
	)
	(paper "A4")
	(title_block
		(title "03242023_DA0F0TMBIJ0_F0T_Motherboard_J_brd_V01_OCP.brd")
		(comment 1 "Grand Teton / footprint 1508 of 6105 (J20), pads 183-228 of 291")
	)
	(layers
		(0 "F.Cu" signal "TOP")
		(4 "In1.Cu" signal "GND")
		(6 "In2.Cu" signal "IN1")
		(8 "In3.Cu" signal "GND1")
		(10 "In4.Cu" signal "IN2")
		(12 "In5.Cu" signal "GND2")
		(14 "In6.Cu" signal "IN3")
		(16 "In7.Cu" signal "GND3")
		(18 "In8.Cu" signal "VCC")
		(20 "In9.Cu" signal "VCC1")
		(22 "In10.Cu" signal "GND4")
		(24 "In11.Cu" signal "IN4")
		(26 "In12.Cu" signal "GND5")
		(28 "In13.Cu" signal "IN5")
		(30 "In14.Cu" signal "GND6")
		(32 "In15.Cu" signal "IN6")
		(34 "In16.Cu" signal "GND7")
		(2 "B.Cu" signal "BOTTOM")
		(9 "F.Adhes" user "F.Adhesive")
		(11 "B.Adhes" user "B.Adhesive")
		(13 "F.Paste" user "Package Geometry/Pastemask Top")
		(15 "B.Paste" user "Package Geometry/Pastemask Bottom")
		(5 "F.SilkS" user "Ref Des/Silkscreen Top")
		(7 "B.SilkS" user "Ref Des/Silkscreen Bottom")
		(1 "F.Mask" user "Board Geometry/Soldermask Top")
		(3 "B.Mask" user "Board Geometry/Soldermask Bottom")
		(17 "Dwgs.User" user "User.Drawings")
		(19 "Cmts.User" user "User.Comments")
		(21 "Eco1.User" user "User.Eco1")
		(23 "Eco2.User" user "User.Eco2")
		(25 "Edge.Cuts" user "Board Geometry/Outline")
		(27 "Margin" user)
		(31 "F.CrtYd" user "Package Geometry/Place Bound Top")
		(29 "B.CrtYd" user "Package Geometry/Place Bound Bottom")
		(35 "F.Fab" user "Ref Des/Assembly Top")
		(33 "B.Fab" user "Ref Des/Assembly Bottom")
	)
	(footprint ""
		(layer "F.Cu")
		(at 47.90948 -258.091686)
		(property "Reference" "J20"
			(at -2.74066 -81.678272 0)
			(unlocked yes)
			(layer "F.SilkS")
			(effects
				(font
					(size 0.7874 0.5842)
					(thickness 0.1524)
				)
				(justify left)
			)
		)
		(property "Value" ""
			(at 0 0 0)
			(layer "F.Fab")
			(effects
				(font
					(size 1.27 1.27)
				)
			)
		)
		(duplicate_pad_numbers_are_jumpers no)
		(pad "183" smd rect
			(at 2.050034 -31.025084 270)
			(size 0.519938 1.4986)
			(layers "F.Cu" "F.Mask" "F.Paste")
			(net "M_B_CPU1_SA_DQ<23>")
		)
		(pad "184" smd rect
			(at 2.050034 -30.174946 270)
			(size 0.519938 1.4986)
			(layers "F.Cu" "F.Mask" "F.Paste")
			(net "GND")
		)
		(pad "185" smd rect
			(at 2.050034 -29.325062 270)
			(size 0.519938 1.4986)
			(layers "F.Cu" "F.Mask" "F.Paste")
			(net "M_B_CPU1_SA_DQ<26>")
		)
		(pad "186" smd rect
			(at 2.050034 -28.474924 270)
			(size 0.519938 1.4986)
			(layers "F.Cu" "F.Mask" "F.Paste")
			(net "GND")
		)
		(pad "187" smd rect
			(at 2.050034 -27.62504 270)
			(size 0.519938 1.4986)
			(layers "F.Cu" "F.Mask" "F.Paste")
			(net "M_B_CPU1_SA_DQ<27>")
		)
		(pad "188" smd rect
			(at 2.050034 -26.774902 270)
			(size 0.519938 1.4986)
			(layers "F.Cu" "F.Mask" "F.Paste")
			(net "GND")
		)
		(pad "189" smd rect
			(at 2.050034 -25.925018 270)
			(size 0.519938 1.4986)
			(layers "F.Cu" "F.Mask" "F.Paste")
			(net "M_B_CPU1_SA_DQS_DN<8>")
		)
		(pad "190" smd rect
			(at 2.050034 -25.07488 270)
			(size 0.519938 1.4986)
			(layers "F.Cu" "F.Mask" "F.Paste")
			(net "M_B_CPU1_SA_DQS_DP<8>")
		)
		(pad "191" smd rect
			(at 2.050034 -24.224996 270)
			(size 0.519938 1.4986)
			(layers "F.Cu" "F.Mask" "F.Paste")
			(net "GND")
		)
		(pad "192" smd rect
			(at 2.050034 -23.375112 270)
			(size 0.519938 1.4986)
			(layers "F.Cu" "F.Mask" "F.Paste")
			(net "M_B_CPU1_SA_DQ<30>")
		)
		(pad "193" smd rect
			(at 2.050034 -22.524974 270)
			(size 0.519938 1.4986)
			(layers "F.Cu" "F.Mask" "F.Paste")
			(net "GND")
		)
		(pad "194" smd rect
			(at 2.050034 -21.67509 270)
			(size 0.519938 1.4986)
			(layers "F.Cu" "F.Mask" "F.Paste")
			(net "M_B_CPU1_SA_DQ<31>")
		)
		(pad "195" smd rect
			(at 2.050034 -20.824952 270)
			(size 0.519938 1.4986)
			(layers "F.Cu" "F.Mask" "F.Paste")
			(net "GND")
		)
		(pad "196" smd rect
			(at 2.050034 -19.975068 270)
			(size 0.519938 1.4986)
			(layers "F.Cu" "F.Mask" "F.Paste")
			(net "M_B_CPU1_SA_CB<2>")
		)
		(pad "197" smd rect
			(at 2.050034 -19.12493 270)
			(size 0.519938 1.4986)
			(layers "F.Cu" "F.Mask" "F.Paste")
			(net "GND")
		)
		(pad "198" smd rect
			(at 2.050034 -18.275046 270)
			(size 0.519938 1.4986)
			(layers "F.Cu" "F.Mask" "F.Paste")
			(net "M_B_CPU1_SA_CB<3>")
		)
		(pad "199" smd rect
			(at 2.050034 -17.424908 270)
			(size 0.519938 1.4986)
			(layers "F.Cu" "F.Mask" "F.Paste")
			(net "GND")
		)
		(pad "200" smd rect
			(at 2.050034 -16.575024 270)
			(size 0.519938 1.4986)
			(layers "F.Cu" "F.Mask" "F.Paste")
			(net "M_B_CPU1_SA_DQS_DN<9>")
		)
		(pad "201" smd rect
			(at 2.050034 -15.724886 270)
			(size 0.519938 1.4986)
			(layers "F.Cu" "F.Mask" "F.Paste")
			(net "M_B_CPU1_SA_DQS_DP<9>")
		)
		(pad "202" smd rect
			(at 2.050034 -14.875002 270)
			(size 0.519938 1.4986)
			(layers "F.Cu" "F.Mask" "F.Paste")
			(net "GND")
		)
		(pad "203" smd rect
			(at 2.050034 -14.025118 270)
			(size 0.519938 1.4986)
			(layers "F.Cu" "F.Mask" "F.Paste")
			(net "M_B_CPU1_SA_CB<6>")
		)
		(pad "204" smd rect
			(at 2.050034 -13.17498 270)
			(size 0.519938 1.4986)
			(layers "F.Cu" "F.Mask" "F.Paste")
			(net "GND")
		)
		(pad "205" smd rect
			(at 2.050034 -12.325096 270)
			(size 0.519938 1.4986)
			(layers "F.Cu" "F.Mask" "F.Paste")
			(net "M_B_CPU1_SA_CB<7>")
		)
		(pad "206" smd rect
			(at 2.050034 -11.474958 270)
			(size 0.519938 1.4986)
			(layers "F.Cu" "F.Mask" "F.Paste")
			(net "GND")
		)
		(pad "207" smd rect
			(at 2.050034 -10.625074 270)
			(size 0.519938 1.4986)
			(layers "F.Cu" "F.Mask" "F.Paste")
			(net "RST_M_AB_CPU1_FPGA_N")
		)
		(pad "208" smd rect
			(at 2.050034 -9.774936 270)
			(size 0.519938 1.4986)
			(layers "F.Cu" "F.Mask" "F.Paste")
			(net "GND")
		)
		(pad "209" smd rect
			(at 2.050034 -8.925052 270)
			(size 0.519938 1.4986)
			(layers "F.Cu" "F.Mask" "F.Paste")
			(net "M_B_CPU1_SA_CS_N<3>")
		)
		(pad "210" smd rect
			(at 2.050034 -8.074914 270)
			(size 0.519938 1.4986)
			(layers "F.Cu" "F.Mask" "F.Paste")
			(net "GND")
		)
		(pad "211" smd rect
			(at 2.050034 -7.22503 270)
			(size 0.519938 1.4986)
			(layers "F.Cu" "F.Mask" "F.Paste")
			(net "M_B_CPU1_SA_CA<1>")
		)
		(pad "212" smd rect
			(at 2.050034 -6.374892 270)
			(size 0.519938 1.4986)
			(layers "F.Cu" "F.Mask" "F.Paste")
			(net "GND")
		)
		(pad "213" smd rect
			(at 2.050034 -5.525008 270)
			(size 0.519938 1.4986)
			(layers "F.Cu" "F.Mask" "F.Paste")
			(net "M_B_CPU1_SA_CA<3>")
		)
		(pad "214" smd rect
			(at 2.050034 -4.675124 270)
			(size 0.519938 1.4986)
			(layers "F.Cu" "F.Mask" "F.Paste")
			(net "GND")
		)
		(pad "215" smd rect
			(at 2.050034 -3.824986 270)
			(size 0.519938 1.4986)
			(layers "F.Cu" "F.Mask" "F.Paste")
			(net "M_B_CPU1_SA_CA<5>")
		)
		(pad "216" smd rect
			(at 2.050034 -2.975102 270)
			(size 0.519938 1.4986)
			(layers "F.Cu" "F.Mask" "F.Paste")
			(net "GND")
		)
		(pad "217" smd rect
			(at 2.050034 -2.124964 270)
			(size 0.519938 1.4986)
			(layers "F.Cu" "F.Mask" "F.Paste")
			(net "M_B_CPU1_CLK_DP<1>")
		)
		(pad "218" smd rect
			(at 2.050034 -1.27508 270)
			(size 0.519938 1.4986)
			(layers "F.Cu" "F.Mask" "F.Paste")
			(net "M_B_CPU1_CLK_DN<1>")
		)
		(pad "219" smd rect
			(at 2.050034 -0.424942 270)
			(size 0.519938 1.4986)
			(layers "F.Cu" "F.Mask" "F.Paste")
			(net "GND")
		)
		(pad "220" smd rect
			(at 2.050034 5.525008 270)
			(size 0.519938 1.4986)
			(layers "F.Cu" "F.Mask" "F.Paste")
			(net "TP_CHB_CPU1_DIMM2_FRU_4")
		)
		(pad "221" smd rect
			(at 2.050034 6.374892 270)
			(size 0.519938 1.4986)
			(layers "F.Cu" "F.Mask" "F.Paste")
			(net "M_B_CPU1_SB_CA<1>")
		)
		(pad "222" smd rect
			(at 2.050034 7.22503 270)
			(size 0.519938 1.4986)
			(layers "F.Cu" "F.Mask" "F.Paste")
			(net "GND")
		)
		(pad "223" smd rect
			(at 2.050034 8.074914 270)
			(size 0.519938 1.4986)
			(layers "F.Cu" "F.Mask" "F.Paste")
			(net "M_B_CPU1_SB_CA<3>")
		)
		(pad "224" smd rect
			(at 2.050034 8.925052 270)
			(size 0.519938 1.4986)
			(layers "F.Cu" "F.Mask" "F.Paste")
			(net "GND")
		)
		(pad "225" smd rect
			(at 2.050034 9.774936 270)
			(size 0.519938 1.4986)
			(layers "F.Cu" "F.Mask" "F.Paste")
			(net "M_B_CPU1_SB_CA<5>")
		)
		(pad "226" smd rect
			(at 2.050034 10.625074 270)
			(size 0.519938 1.4986)
			(layers "F.Cu" "F.Mask" "F.Paste")
			(net "GND")
		)
		(pad "227" smd rect
			(at 2.050034 11.474958 270)
			(size 0.519938 1.4986)
			(layers "F.Cu" "F.Mask" "F.Paste")
			(net "M_B_CPU1_SB_PAR")
		)
		(pad "228" smd rect
			(at 2.050034 12.325096 270)
			(size 0.519938 1.4986)
			(layers "F.Cu" "F.Mask" "F.Paste")
			(net "GND")
		)
	)
)
